(kicad_pcb
	(version 20241229)
	(generator "pcbnew")
	(generator_version "9.0")
	(general
		(thickness 1.61)
		(legacy_teardrops no)
	)
	(paper "A3")
	(title_block
		(title "RDIMM DDR5 Tester")
		(date "2026-05-21")
		(rev "2.2.0")
		(company "Antmicro")
		(comment 9 "footprint 375 of 796 (U6), pads 1-73 of 73")
	)
	(layers
		(0 "F.Cu" signal)
		(4 "In1.Cu" power)
		(6 "In2.Cu" mixed)
		(8 "In3.Cu" power)
		(10 "In4.Cu" mixed)
		(12 "In5.Cu" power)
		(14 "In6.Cu" mixed)
		(16 "In7.Cu" power)
		(18 "In8.Cu" power)
		(20 "In9.Cu" mixed)
		(22 "In10.Cu" power)
		(2 "B.Cu" signal)
		(9 "F.Adhes" user "F.Adhesive")
		(11 "B.Adhes" user "B.Adhesive")
		(13 "F.Paste" user)
		(15 "B.Paste" user)
		(5 "F.SilkS" user "F.Silkscreen")
		(7 "B.SilkS" user "B.Silkscreen")
		(1 "F.Mask" user)
		(3 "B.Mask" user)
		(17 "Dwgs.User" user "User.Drawings")
		(19 "Cmts.User" user "User.Comments")
		(21 "Eco1.User" user "User.Eco1")
		(23 "Eco2.User" user "User.Eco2")
		(25 "Edge.Cuts" user)
		(27 "Margin" user)
		(31 "F.CrtYd" user "F.Courtyard")
		(29 "B.CrtYd" user "B.Courtyard")
		(35 "F.Fab" user)
		(33 "B.Fab" user)
	)
	(footprint "antmicro-footprints:QFN-56-1EP_8x8mm_P0.5mm"
		(layer "F.Cu")
		(at 141.684 162.835)
		(descr "QFN 56 Pin")
		(tags "QFN")
		(property "Reference" "U6"
			(at 2.940499 5.314 0)
			(layer "F.SilkS")
			(effects
				(font
					(size 0.7 0.7)
					(thickness 0.15)
				)
				(justify left bottom)
			)
		)
		(property "Value" "FT4232H_VQFN"
			(at 0 5.32 0)
			(layer "F.Fab")
			(effects
				(font
					(size 0.7 0.7)
					(thickness 0.15)
				)
				(justify left bottom)
			)
		)
		(property "Datasheet" "https://www.ftdichip.com/Support/Documents/DataSheets/ICs/DS_FT4232H.pdf"
			(at 0 0 0)
			(layer "F.Fab")
			(hide yes)
			(effects
				(font
					(size 1.27 1.27)
					(thickness 0.15)
				)
			)
		)
		(property "Manufacturer" "FTDI Chip"
			(at 0 0 0)
			(unlocked yes)
			(layer "F.Fab")
			(hide yes)
			(effects
				(font
					(size 1 1)
					(thickness 0.15)
				)
			)
		)
		(property "MPN" "FT4232H-56Q-REEL"
			(at 0 0 0)
			(unlocked yes)
			(layer "F.Fab")
			(hide yes)
			(effects
				(font
					(size 1 1)
					(thickness 0.15)
				)
			)
		)
		(property "Author" "Antmicro"
			(at 0 0 0)
			(unlocked yes)
			(layer "F.Fab")
			(hide yes)
			(effects
				(font
					(size 1 1)
					(thickness 0.15)
				)
			)
		)
		(property "License" "Apache-2.0"
			(at 0 0 0)
			(unlocked yes)
			(layer "F.Fab")
			(hide yes)
			(effects
				(font
					(size 1 1)
					(thickness 0.15)
				)
			)
		)
		(sheetname "/Debug FTDI + VNA/")
		(sheetfile "debug-ftdi.kicad_sch")
		(attr smd)
		(pad "" smd roundrect
			(at -2.101 -2.101)
			(size 1.13 1.13)
			(layers "F.Paste")
			(roundrect_rratio 0.221239)
		)
		(pad "" smd roundrect
			(at -2.101 -0.7)
			(size 1.13 1.13)
			(layers "F.Paste")
			(roundrect_rratio 0.221239)
		)
		(pad "" smd roundrect
			(at -2.101 0.699)
			(size 1.13 1.13)
			(layers "F.Paste")
			(roundrect_rratio 0.221239)
		)
		(pad "" smd roundrect
			(at -2.101 2.1)
			(size 1.13 1.13)
			(layers "F.Paste")
			(roundrect_rratio 0.221239)
		)
		(pad "" smd roundrect
			(at -0.7 -2.101)
			(size 1.13 1.13)
			(layers "F.Paste")
			(roundrect_rratio 0.221239)
		)
		(pad "" smd roundrect
			(at -0.7 -0.7)
			(size 1.13 1.13)
			(layers "F.Paste")
			(roundrect_rratio 0.221239)
		)
		(pad "" smd roundrect
			(at -0.7 0.699)
			(size 1.13 1.13)
			(layers "F.Paste")
			(roundrect_rratio 0.221239)
		)
		(pad "" smd roundrect
			(at -0.7 2.1)
			(size 1.13 1.13)
			(layers "F.Paste")
			(roundrect_rratio 0.221239)
		)
		(pad "" smd roundrect
			(at 0.699 -2.101)
			(size 1.13 1.13)
			(layers "F.Paste")
			(roundrect_rratio 0.221239)
		)
		(pad "" smd roundrect
			(at 0.699 -0.7)
			(size 1.13 1.13)
			(layers "F.Paste")
			(roundrect_rratio 0.221239)
		)
		(pad "" smd roundrect
			(at 0.699 0.699)
			(size 1.13 1.13)
			(layers "F.Paste")
			(roundrect_rratio 0.221239)
		)
		(pad "" smd roundrect
			(at 0.699 2.1)
			(size 1.13 1.13)
			(layers "F.Paste")
			(roundrect_rratio 0.221239)
		)
		(pad "" smd roundrect
			(at 2.1 -2.101)
			(size 1.13 1.13)
			(layers "F.Paste")
			(roundrect_rratio 0.221239)
		)
		(pad "" smd roundrect
			(at 2.1 -0.7)
			(size 1.13 1.13)
			(layers "F.Paste")
			(roundrect_rratio 0.221239)
		)
		(pad "" smd roundrect
			(at 2.1 0.699)
			(size 1.13 1.13)
			(layers "F.Paste")
			(roundrect_rratio 0.221239)
		)
		(pad "" smd roundrect
			(at 2.1 2.1)
			(size 1.13 1.13)
			(layers "F.Paste")
			(roundrect_rratio 0.221239)
		)
		(pad "1" smd roundrect
			(at -3.938 -3.25)
			(size 0.875 0.3)
			(layers "F.Cu" "F.Mask" "F.Paste")
			(roundrect_rratio 0.25)
			(net 780 "/Debug FTDI + VNA/FTDI_EECS")
			(pinfunction "EECS")
			(pintype "bidirectional")
		)
		(pad "2" smd roundrect
			(at -3.938 -2.75)
			(size 0.875 0.3)
			(layers "F.Cu" "F.Mask" "F.Paste")
			(roundrect_rratio 0.25)
			(net 34 "/Debug FTDI + VNA/FTDI_VCORE")
			(pinfunction "V_{CORE}")
			(pintype "power_in")
		)
		(pad "3" smd roundrect
			(at -3.938 -2.25)
			(size 0.875 0.3)
			(layers "F.Cu" "F.Mask" "F.Paste")
			(roundrect_rratio 0.25)
			(net 4 "/Debug FTDI + VNA/FTDI_XI")
			(pinfunction "OSCI")
			(pintype "input")
		)
		(pad "4" smd roundrect
			(at -3.938 -1.75)
			(size 0.875 0.3)
			(layers "F.Cu" "F.Mask" "F.Paste")
			(roundrect_rratio 0.25)
			(net 7 "/Debug FTDI + VNA/FTDI_XO")
			(pinfunction "OSCO")
			(pintype "output")
		)
		(pad "5" smd roundrect
			(at -3.938 -1.25)
			(size 0.875 0.3)
			(layers "F.Cu" "F.Mask" "F.Paste")
			(roundrect_rratio 0.25)
			(net 5 "/Debug FTDI + VNA/FTDI_VPHY")
			(pinfunction "V_{PHY}")
			(pintype "power_in")
		)
		(pad "6" smd roundrect
			(at -3.938 -0.75)
			(size 0.875 0.3)
			(layers "F.Cu" "F.Mask" "F.Paste")
			(roundrect_rratio 0.25)
			(net 293 "Net-(U6-REF)")
			(pinfunction "REF")
			(pintype "input")
		)
		(pad "7" smd roundrect
			(at -3.938 -0.25)
			(size 0.875 0.3)
			(layers "F.Cu" "F.Mask" "F.Paste")
			(roundrect_rratio 0.25)
			(net 365 "/Debug FTDI + VNA/DBG_USB_N")
			(pinfunction "D-")
			(pintype "bidirectional")
		)
		(pad "8" smd roundrect
			(at -3.938 0.249)
			(size 0.875 0.3)
			(layers "F.Cu" "F.Mask" "F.Paste")
			(roundrect_rratio 0.25)
			(net 364 "/Debug FTDI + VNA/DBG_USB_P")
			(pinfunction "D+")
			(pintype "bidirectional")
		)
		(pad "9" smd roundrect
			(at -3.938 0.749)
			(size 0.875 0.3)
			(layers "F.Cu" "F.Mask" "F.Paste")
			(roundrect_rratio 0.25)
			(net 3 "/Debug FTDI + VNA/FTDI_VPLL")
			(pinfunction "V_{PLL}")
			(pintype "power_in")
		)
		(pad "10" smd roundrect
			(at -3.938 1.249)
			(size 0.875 0.3)
			(layers "F.Cu" "F.Mask" "F.Paste")
			(roundrect_rratio 0.25)
			(net 1 "GND")
			(pinfunction "TEST")
			(pintype "input")
		)
		(pad "11" smd roundrect
			(at -3.938 1.749)
			(size 0.875 0.3)
			(layers "F.Cu" "F.Mask" "F.Paste")
			(roundrect_rratio 0.25)
			(net 289 "Net-(U6-~{RESET})")
			(pinfunction "~{RESET}")
			(pintype "input")
		)
		(pad "12" smd roundrect
			(at -3.938 2.249)
			(size 0.875 0.3)
			(layers "F.Cu" "F.Mask" "F.Paste")
			(roundrect_rratio 0.25)
			(net 781 "/Debug FTDI + VNA/FTDI_JTAG_TCK")
			(pinfunction "ADBUS0")
			(pintype "bidirectional")
		)
		(pad "13" smd roundrect
			(at -3.938 2.749)
			(size 0.875 0.3)
			(layers "F.Cu" "F.Mask" "F.Paste")
			(roundrect_rratio 0.25)
			(net 786 "/Debug FTDI + VNA/FTDI_JTAG_TDI")
			(pinfunction "ADBUS1")
			(pintype "bidirectional")
		)
		(pad "14" smd roundrect
			(at -3.938 3.249)
			(size 0.875 0.3)
			(layers "F.Cu" "F.Mask" "F.Paste")
			(roundrect_rratio 0.25)
			(net 787 "/Debug FTDI + VNA/FTDI_JTAG_TDO")
			(pinfunction "ADBUS2")
			(pintype "bidirectional")
		)
		(pad "15" smd roundrect
			(at -3.25 3.937 90)
			(size 0.875 0.3)
			(layers "F.Cu" "F.Mask" "F.Paste")
			(roundrect_rratio 0.25)
			(net 788 "/Debug FTDI + VNA/FTDI_JTAG_TMS")
			(pinfunction "ADBUS3")
			(pintype "bidirectional")
		)
		(pad "16" smd roundrect
			(at -2.75 3.937 90)
			(size 0.875 0.3)
			(layers "F.Cu" "F.Mask" "F.Paste")
			(roundrect_rratio 0.25)
			(net 6 "/Debug FTDI + VNA/FTDI_3V3")
			(pinfunction "V_{CCIO}")
			(pintype "power_in")
		)
		(pad "17" smd roundrect
			(at -2.25 3.937 90)
			(size 0.875 0.3)
			(layers "F.Cu" "F.Mask" "F.Paste")
			(roundrect_rratio 0.25)
			(net 312 "unconnected-(U6-ADBUS4-Pad17)")
			(pinfunction "ADBUS4")
			(pintype "bidirectional+no_connect")
		)
		(pad "18" smd roundrect
			(at -1.75 3.937 90)
			(size 0.875 0.3)
			(layers "F.Cu" "F.Mask" "F.Paste")
			(roundrect_rratio 0.25)
			(net 776 "/Debug FTDI + VNA/FTDI_JTAG_RST")
			(pinfunction "ADBUS5")
			(pintype "bidirectional")
		)
		(pad "19" smd roundrect
			(at -1.25 3.937 90)
			(size 0.875 0.3)
			(layers "F.Cu" "F.Mask" "F.Paste")
			(roundrect_rratio 0.25)
			(net 313 "unconnected-(U6-ADBUS6-Pad19)")
			(pinfunction "ADBUS6")
			(pintype "bidirectional+no_connect")
		)
		(pad "20" smd roundrect
			(at -0.75 3.937 90)
			(size 0.875 0.3)
			(layers "F.Cu" "F.Mask" "F.Paste")
			(roundrect_rratio 0.25)
			(net 314 "unconnected-(U6-ADBUS7-Pad20)")
			(pinfunction "ADBUS7")
			(pintype "bidirectional+no_connect")
		)
		(pad "21" smd roundrect
			(at -0.25 3.937 90)
			(size 0.875 0.3)
			(layers "F.Cu" "F.Mask" "F.Paste")
			(roundrect_rratio 0.25)
			(net 1 "GND")
			(pinfunction "GND")
			(pintype "power_in")
		)
		(pad "22" smd roundrect
			(at 0.249 3.937 90)
			(size 0.875 0.3)
			(layers "F.Cu" "F.Mask" "F.Paste")
			(roundrect_rratio 0.25)
			(net 379 "/Debug FTDI + VNA/BDBUS0")
			(pinfunction "BDBUS0")
			(pintype "bidirectional")
		)
		(pad "23" smd roundrect
			(at 0.749 3.937 90)
			(size 0.875 0.3)
			(layers "F.Cu" "F.Mask" "F.Paste")
			(roundrect_rratio 0.25)
			(net 390 "/Debug FTDI + VNA/BDBUS1")
			(pinfunction "BDBUS1")
			(pintype "bidirectional")
		)
		(pad "24" smd roundrect
			(at 1.249 3.937 90)
			(size 0.875 0.3)
			(layers "F.Cu" "F.Mask" "F.Paste")
			(roundrect_rratio 0.25)
			(net 392 "/Debug FTDI + VNA/BDBUS2")
			(pinfunction "BDBUS2")
			(pintype "bidirectional")
		)
		(pad "25" smd roundrect
			(at 1.749 3.937 90)
			(size 0.875 0.3)
			(layers "F.Cu" "F.Mask" "F.Paste")
			(roundrect_rratio 0.25)
			(net 407 "/Debug FTDI + VNA/BDBUS3")
			(pinfunction "BDBUS3")
			(pintype "bidirectional")
		)
		(pad "26" smd roundrect
			(at 2.249 3.937 90)
			(size 0.875 0.3)
			(layers "F.Cu" "F.Mask" "F.Paste")
			(roundrect_rratio 0.25)
			(net 315 "unconnected-(U6-BDBUS4-Pad26)")
			(pinfunction "BDBUS4")
			(pintype "bidirectional+no_connect")
		)
		(pad "27" smd roundrect
			(at 2.749 3.937 90)
			(size 0.875 0.3)
			(layers "F.Cu" "F.Mask" "F.Paste")
			(roundrect_rratio 0.25)
			(net 441 "/Debug FTDI + VNA/I2C_EN")
			(pinfunction "BDBUS5")
			(pintype "bidirectional")
		)
		(pad "28" smd roundrect
			(at 3.249 3.937 90)
			(size 0.875 0.3)
			(layers "F.Cu" "F.Mask" "F.Paste")
			(roundrect_rratio 0.25)
			(net 316 "unconnected-(U6-BDBUS6-Pad28)")
			(pinfunction "BDBUS6")
			(pintype "bidirectional+no_connect")
		)
		(pad "29" smd roundrect
			(at 3.937 3.249)
			(size 0.875 0.3)
			(layers "F.Cu" "F.Mask" "F.Paste")
			(roundrect_rratio 0.25)
			(net 317 "unconnected-(U6-BDBUS7-Pad29)")
			(pinfunction "BDBUS7")
			(pintype "bidirectional+no_connect")
		)
		(pad "30" smd roundrect
			(at 3.937 2.749)
			(size 0.875 0.3)
			(layers "F.Cu" "F.Mask" "F.Paste")
			(roundrect_rratio 0.25)
			(net 318 "unconnected-(U6-~{SUSPEND}-Pad30)")
			(pinfunction "~{SUSPEND}")
			(pintype "output+no_connect")
		)
		(pad "31" smd roundrect
			(at 3.937 2.249)
			(size 0.875 0.3)
			(layers "F.Cu" "F.Mask" "F.Paste")
			(roundrect_rratio 0.25)
			(net 34 "/Debug FTDI + VNA/FTDI_VCORE")
			(pinfunction "V_{CORE}")
			(pintype "passive")
		)
		(pad "32" smd roundrect
			(at 3.937 1.749)
			(size 0.875 0.3)
			(layers "F.Cu" "F.Mask" "F.Paste")
			(roundrect_rratio 0.25)
			(net 789 "/Debug FTDI + VNA/FTDI_UART0_TX")
			(pinfunction "CDBUS0")
			(pintype "bidirectional")
		)
		(pad "33" smd roundrect
			(at 3.937 1.249)
			(size 0.875 0.3)
			(layers "F.Cu" "F.Mask" "F.Paste")
			(roundrect_rratio 0.25)
			(net 790 "/Debug FTDI + VNA/FTDI_UART0_RX")
			(pinfunction "CDBUS1")
			(pintype "bidirectional")
		)
		(pad "34" smd roundrect
			(at 3.937 0.749)
			(size 0.875 0.3)
			(layers "F.Cu" "F.Mask" "F.Paste")
			(roundrect_rratio 0.25)
			(net 319 "unconnected-(U6-CDBUS2-Pad34)")
			(pinfunction "CDBUS2")
			(pintype "bidirectional+no_connect")
		)
		(pad "35" smd roundrect
			(at 3.937 0.249)
			(size 0.875 0.3)
			(layers "F.Cu" "F.Mask" "F.Paste")
			(roundrect_rratio 0.25)
			(net 320 "unconnected-(U6-CDBUS3-Pad35)")
			(pinfunction "CDBUS3")
			(pintype "bidirectional+no_connect")
		)
		(pad "36" smd roundrect
			(at 3.937 -0.25)
			(size 0.875 0.3)
			(layers "F.Cu" "F.Mask" "F.Paste")
			(roundrect_rratio 0.25)
			(net 6 "/Debug FTDI + VNA/FTDI_3V3")
			(pinfunction "V_{CCIO}")
			(pintype "passive")
		)
		(pad "37" smd roundrect
			(at 3.937 -0.75)
			(size 0.875 0.3)
			(layers "F.Cu" "F.Mask" "F.Paste")
			(roundrect_rratio 0.25)
			(net 326 "unconnected-(U6-CDBUS4-Pad37)")
			(pinfunction "CDBUS4")
			(pintype "bidirectional+no_connect")
		)
		(pad "38" smd roundrect
			(at 3.937 -1.25)
			(size 0.875 0.3)
			(layers "F.Cu" "F.Mask" "F.Paste")
			(roundrect_rratio 0.25)
			(net 327 "unconnected-(U6-CDBUS5-Pad38)")
			(pinfunction "CDBUS5")
			(pintype "bidirectional+no_connect")
		)
		(pad "39" smd roundrect
			(at 3.937 -1.75)
			(size 0.875 0.3)
			(layers "F.Cu" "F.Mask" "F.Paste")
			(roundrect_rratio 0.25)
			(net 328 "unconnected-(U6-CDBUS6-Pad39)")
			(pinfunction "CDBUS6")
			(pintype "bidirectional+no_connect")
		)
		(pad "40" smd roundrect
			(at 3.937 -2.25)
			(size 0.875 0.3)
			(layers "F.Cu" "F.Mask" "F.Paste")
			(roundrect_rratio 0.25)
			(net 329 "unconnected-(U6-CDBUS7-Pad40)")
			(pinfunction "CDBUS7")
			(pintype "bidirectional+no_connect")
		)
		(pad "41" smd roundrect
			(at 3.937 -2.75)
			(size 0.875 0.3)
			(layers "F.Cu" "F.Mask" "F.Paste")
			(roundrect_rratio 0.25)
			(net 1 "GND")
			(pinfunction "GND")
			(pintype "passive")
		)
		(pad "42" smd roundrect
			(at 3.937 -3.25)
			(size 0.875 0.3)
			(layers "F.Cu" "F.Mask" "F.Paste")
			(roundrect_rratio 0.25)
			(net 791 "/Debug FTDI + VNA/FTDI_UART1_TX")
			(pinfunction "DDBUS0")
			(pintype "bidirectional")
		)
		(pad "43" smd roundrect
			(at 3.249 -3.938 90)
			(size 0.875 0.3)
			(layers "F.Cu" "F.Mask" "F.Paste")
			(roundrect_rratio 0.25)
			(net 34 "/Debug FTDI + VNA/FTDI_VCORE")
			(pinfunction "V_{REGOUT}")
			(pintype "power_out")
		)
		(pad "44" smd roundrect
			(at 2.749 -3.938 90)
			(size 0.875 0.3)
			(layers "F.Cu" "F.Mask" "F.Paste")
			(roundrect_rratio 0.25)
			(net 6 "/Debug FTDI + VNA/FTDI_3V3")
			(pinfunction "V_{REGIN}")
			(pintype "power_in")
		)
		(pad "45" smd roundrect
			(at 2.249 -3.938 90)
			(size 0.875 0.3)
			(layers "F.Cu" "F.Mask" "F.Paste")
			(roundrect_rratio 0.25)
			(net 1 "GND")
			(pinfunction "GND")
			(pintype "passive")
		)
		(pad "46" smd roundrect
			(at 1.749 -3.938 90)
			(size 0.875 0.3)
			(layers "F.Cu" "F.Mask" "F.Paste")
			(roundrect_rratio 0.25)
			(net 792 "/Debug FTDI + VNA/FTDI_UART1_RX")
			(pinfunction "DDBUS1")
			(pintype "bidirectional")
		)
		(pad "47" smd roundrect
			(at 1.249 -3.938 90)
			(size 0.875 0.3)
			(layers "F.Cu" "F.Mask" "F.Paste")
			(roundrect_rratio 0.25)
			(net 343 "unconnected-(U6-DDBUS2-Pad47)")
			(pinfunction "DDBUS2")
			(pintype "bidirectional+no_connect")
		)
		(pad "48" smd roundrect
			(at 0.749 -3.938 90)
			(size 0.875 0.3)
			(layers "F.Cu" "F.Mask" "F.Paste")
			(roundrect_rratio 0.25)
			(net 345 "unconnected-(U6-DDBUS3-Pad48)")
			(pinfunction "DDBUS3")
			(pintype "bidirectional+no_connect")
		)
		(pad "49" smd roundrect
			(at 0.249 -3.938 90)
			(size 0.875 0.3)
			(layers "F.Cu" "F.Mask" "F.Paste")
			(roundrect_rratio 0.25)
			(net 347 "unconnected-(U6-DDBUS4-Pad49)")
			(pinfunction "DDBUS4")
			(pintype "bidirectional+no_connect")
		)
		(pad "50" smd roundrect
			(at -0.25 -3.938 90)
			(size 0.875 0.3)
			(layers "F.Cu" "F.Mask" "F.Paste")
			(roundrect_rratio 0.25)
			(net 6 "/Debug FTDI + VNA/FTDI_3V3")
			(pinfunction "V_{CCIO}")
			(pintype "passive")
		)
		(pad "51" smd roundrect
			(at -0.75 -3.938 90)
			(size 0.875 0.3)
			(layers "F.Cu" "F.Mask" "F.Paste")
			(roundrect_rratio 0.25)
			(net 411 "unconnected-(U6-DDBUS5-Pad51)")
			(pinfunction "DDBUS5")
			(pintype "bidirectional+no_connect")
		)
		(pad "52" smd roundrect
			(at -1.25 -3.938 90)
			(size 0.875 0.3)
			(layers "F.Cu" "F.Mask" "F.Paste")
			(roundrect_rratio 0.25)
			(net 412 "unconnected-(U6-DDBUS6-Pad52)")
			(pinfunction "DDBUS6")
			(pintype "bidirectional+no_connect")
		)
		(pad "53" smd roundrect
			(at -1.75 -3.938 90)
			(size 0.875 0.3)
			(layers "F.Cu" "F.Mask" "F.Paste")
			(roundrect_rratio 0.25)
			(net 413 "unconnected-(U6-DDBUS7-Pad53)")
			(pinfunction "DDBUS7")
			(pintype "bidirectional+no_connect")
		)
		(pad "54" smd roundrect
			(at -2.25 -3.938 90)
			(size 0.875 0.3)
			(layers "F.Cu" "F.Mask" "F.Paste")
			(roundrect_rratio 0.25)
			(net 372 "/Debug FTDI + VNA/FTDI_PWREN")
			(pinfunction "~{PWR_{EN}}")
			(pintype "output")
		)
		(pad "55" smd roundrect
			(at -2.75 -3.938 90)
			(size 0.875 0.3)
			(layers "F.Cu" "F.Mask" "F.Paste")
			(roundrect_rratio 0.25)
			(net 793 "/Debug FTDI + VNA/FTDI_EEDAT")
			(pinfunction "EEDATA")
			(pintype "bidirectional")
		)
		(pad "56" smd roundrect
			(at -3.25 -3.938 90)
			(size 0.875 0.3)
			(layers "F.Cu" "F.Mask" "F.Paste")
			(roundrect_rratio 0.25)
			(net 794 "/Debug FTDI + VNA/FTDI_EECLK")
			(pinfunction "EECLK")
			(pintype "output")
		)
		(pad "57" smd rect
			(at 0 0)
			(size 5.9 5.9)
			(layers "F.Cu" "F.Mask")
			(net 1 "GND")
			(pinfunction "GND")
			(pintype "passive")
		)
	)
)
